# T6G (Grand Teton) — schematic netlist excerpt (pin names and nets, part order shuffled) for the footprints in the layout excerpt that follows; sources: Cadence DE-HDL packaged netlist, KiCad conversion of 04192023_DAF0TMB3IC0_F0TG_MB_C_brd_V02_OCP.brd

PR8073  Q_RES  1K 1% CHIP  pkg 0402LF  page 190 : A = P3V3_AUX ; B = PWRGD_P3V3_AUX_R1
R497  Q_RES  33 5% CHIP  pkg 0402LF  page 54 : A = APML_CPU1_ALERT_N ; B = APML_CPU1_ALERT_R_N

(kicad_pcb
	(version 20260206)
	(generator "pcbnew")
	(generator_version "10.0")
	(general
		(thickness 1.6)
		(legacy_teardrops no)
	)
	(paper "A4")
	(title_block
		(title "04192023_DAF0TMB3IC0_F0TG_MB_C_brd_V02_OCP.brd")
		(comment 1 "Grand Teton / footprints 7046-7047 of 8354")
	)
	(layers
		(0 "F.Cu" signal "TOP")
		(4 "In1.Cu" signal "GND")
		(6 "In2.Cu" signal "IN1")
		(8 "In3.Cu" signal "GND1")
		(10 "In4.Cu" signal "IN2")
		(12 "In5.Cu" signal "GND2")
		(14 "In6.Cu" signal "IN3")
		(16 "In7.Cu" signal "GND3")
		(18 "In8.Cu" signal "VCC")
		(20 "In9.Cu" signal "VCC1")
		(22 "In10.Cu" signal "GND4")
		(24 "In11.Cu" signal "IN4")
		(26 "In12.Cu" signal "GND5")
		(28 "In13.Cu" signal "IN5")
		(30 "In14.Cu" signal "GND6")
		(32 "In15.Cu" signal "IN6")
		(34 "In16.Cu" signal "GND7")
		(2 "B.Cu" signal "BOTTOM")
		(9 "F.Adhes" user "F.Adhesive")
		(11 "B.Adhes" user "B.Adhesive")
		(13 "F.Paste" user "Package Geometry/Pastemask Top")
		(15 "B.Paste" user "Package Geometry/Pastemask Bottom")
		(5 "F.SilkS" user "Ref Des/Silkscreen Top")
		(7 "B.SilkS" user "Ref Des/Silkscreen Bottom")
		(1 "F.Mask" user "Board Geometry/Soldermask Top")
		(3 "B.Mask" user "Board Geometry/Soldermask Bottom")
		(17 "Dwgs.User" user "User.Drawings")
		(19 "Cmts.User" user "User.Comments")
		(21 "Eco1.User" user "User.Eco1")
		(23 "Eco2.User" user "User.Eco2")
		(25 "Edge.Cuts" user "Board Geometry/Outline")
		(27 "Margin" user)
		(31 "F.CrtYd" user "Package Geometry/Place Bound Top")
		(29 "B.CrtYd" user "Package Geometry/Place Bound Bottom")
		(35 "F.Fab" user "Ref Des/Assembly Top")
		(33 "B.Fab" user "Ref Des/Assembly Bottom")
	)
	(footprint ""
		(layer "B.Cu")
		(at 185.324496 -133.577076 90)
		(property "Reference" "R497"
			(at 0 0 90)
			(layer "B.SilkS")
			(hide yes)
			(effects
				(font
					(size 1.27 1.27)
				)
				(justify mirror)
			)
		)
		(property "Value" ""
			(at 0 0 90)
			(layer "B.Fab")
			(effects
				(font
					(size 1.27 1.27)
				)
				(justify mirror)
			)
		)
		(duplicate_pad_numbers_are_jumpers no)
		(fp_line
			(start 0.7874 -0.4064)
			(end -0.7874 -0.4064)
			(stroke
				(width 0.1524)
				(type default)
			)
			(layer "B.SilkS")
		)
		(fp_line
			(start -0.7874 -0.4064)
			(end -0.7874 0.4064)
			(stroke
				(width 0.1524)
				(type default)
			)
			(layer "B.SilkS")
		)
		(fp_line
			(start 0.7874 0.4064)
			(end 0.7874 -0.4064)
			(stroke
				(width 0.1524)
				(type default)
			)
			(layer "B.SilkS")
		)
		(fp_line
			(start -0.7874 0.4064)
			(end 0.7874 0.4064)
			(stroke
				(width 0.1524)
				(type default)
			)
			(layer "B.SilkS")
		)
		(fp_line
			(start 0.67945 -0.305054)
			(end 0.12065 -0.305054)
			(stroke
				(width 0.1)
				(type default)
			)
			(layer "B.Fab")
		)
		(fp_line
			(start 0.12065 -0.305054)
			(end 0.12065 -0.2794)
			(stroke
				(width 0.1)
				(type default)
			)
			(layer "B.Fab")
		)
		(fp_line
			(start -0.12065 -0.3048)
			(end -0.67945 -0.3048)
			(stroke
				(width 0.1)
				(type default)
			)
			(layer "B.Fab")
		)
		(fp_line
			(start -0.67945 -0.3048)
			(end -0.67945 0.3048)
			(stroke
				(width 0.1)
				(type default)
			)
			(layer "B.Fab")
		)
		(fp_line
			(start 0.12065 -0.2794)
			(end -0.12065 -0.2794)
			(stroke
				(width 0.1)
				(type default)
			)
			(layer "B.Fab")
		)
		(fp_line
			(start -0.12065 -0.2794)
			(end -0.12065 -0.3048)
			(stroke
				(width 0.1)
				(type default)
			)
			(layer "B.Fab")
		)
		(fp_line
			(start 0.12065 0.2794)
			(end 0.12065 0.3048)
			(stroke
				(width 0.1)
				(type default)
			)
			(layer "B.Fab")
		)
		(fp_line
			(start -0.120396 0.2794)
			(end 0.12065 0.2794)
			(stroke
				(width 0.1)
				(type default)
			)
			(layer "B.Fab")
		)
		(fp_line
			(start 0.67945 0.3048)
			(end 0.67945 -0.305054)
			(stroke
				(width 0.1)
				(type default)
			)
			(layer "B.Fab")
		)
		(fp_line
			(start 0.12065 0.3048)
			(end 0.67945 0.3048)
			(stroke
				(width 0.1)
				(type default)
			)
			(layer "B.Fab")
		)
		(fp_line
			(start -0.120396 0.3048)
			(end -0.120396 0.2794)
			(stroke
				(width 0.1)
				(type default)
			)
			(layer "B.Fab")
		)
		(fp_line
			(start -0.67945 0.3048)
			(end -0.120396 0.3048)
			(stroke
				(width 0.1)
				(type default)
			)
			(layer "B.Fab")
		)
		(pad "1" smd circle
			(at 0.40005 0 270)
			(size 0 0)
			(layers "B.Cu" "B.Mask" "B.Paste")
			(net "APML_CPU1_ALERT_N")
		)
		(pad "2" smd circle
			(at -0.40005 0 270)
			(size 0 0)
			(layers "B.Cu" "B.Mask" "B.Paste")
			(net "APML_CPU1_ALERT_R_N")
		)
	)
	(footprint ""
		(layer "B.Cu")
		(at 460.405988 -43.400726 180)
		(property "Reference" "PR8073"
			(at 0 0 0)
			(layer "B.SilkS")
			(hide yes)
			(effects
				(font
					(size 1.27 1.27)
				)
				(justify mirror)
			)
		)
		(property "Value" ""
			(at 0 0 0)
			(layer "B.Fab")
			(effects
				(font
					(size 1.27 1.27)
				)
				(justify mirror)
			)
		)
		(duplicate_pad_numbers_are_jumpers no)
		(fp_line
			(start 0.7874 0.4064)
			(end 0.7874 -0.4064)
			(stroke
				(width 0.1524)
				(type default)
			)
			(layer "B.SilkS")
		)
		(fp_line
			(start 0.7874 -0.4064)
			(end -0.7874 -0.4064)
			(stroke
				(width 0.1524)
				(type default)
			)
			(layer "B.SilkS")
		)
		(fp_line
			(start -0.7874 0.4064)
			(end 0.7874 0.4064)
			(stroke
				(width 0.1524)
				(type default)
			)
			(layer "B.SilkS")
		)
		(fp_line
			(start -0.7874 -0.4064)
			(end -0.7874 0.4064)
			(stroke
				(width 0.1524)
				(type default)
			)
			(layer "B.SilkS")
		)
		(fp_line
			(start 0.67945 0.3048)
			(end 0.67945 -0.305054)
			(stroke
				(width 0.1)
				(type default)
			)
			(layer "B.Fab")
		)
		(fp_line
			(start 0.67945 -0.305054)
			(end 0.12065 -0.305054)
			(stroke
				(width 0.1)
				(type default)
			)
			(layer "B.Fab")
		)
		(fp_line
			(start 0.12065 0.3048)
			(end 0.67945 0.3048)
			(stroke
				(width 0.1)
				(type default)
			)
			(layer "B.Fab")
		)
		(fp_line
			(start 0.12065 0.2794)
			(end 0.12065 0.3048)
			(stroke
				(width 0.1)
				(type default)
			)
			(layer "B.Fab")
		)
		(fp_line
			(start 0.12065 -0.2794)
			(end -0.12065 -0.2794)
			(stroke
				(width 0.1)
				(type default)
			)
			(layer "B.Fab")
		)
		(fp_line
			(start 0.12065 -0.305054)
			(end 0.12065 -0.2794)
			(stroke
				(width 0.1)
				(type default)
			)
			(layer "B.Fab")
		)
		(fp_line
			(start -0.120396 0.3048)
			(end -0.120396 0.2794)
			(stroke
				(width 0.1)
				(type default)
			)
			(layer "B.Fab")
		)
		(fp_line
			(start -0.120396 0.2794)
			(end 0.12065 0.2794)
			(stroke
				(width 0.1)
				(type default)
			)
			(layer "B.Fab")
		)
		(fp_line
			(start -0.12065 -0.2794)
			(end -0.12065 -0.3048)
			(stroke
				(width 0.1)
				(type default)
			)
			(layer "B.Fab")
		)
		(fp_line
			(start -0.12065 -0.3048)
			(end -0.67945 -0.3048)
			(stroke
				(width 0.1)
				(type default)
			)
			(layer "B.Fab")
		)
		(fp_line
			(start -0.67945 0.3048)
			(end -0.120396 0.3048)
			(stroke
				(width 0.1)
				(type default)
			)
			(layer "B.Fab")
		)
		(fp_line
			(start -0.67945 -0.3048)
			(end -0.67945 0.3048)
			(stroke
				(width 0.1)
				(type default)
			)
			(layer "B.Fab")
		)
		(pad "1" smd circle
			(at 0.40005 0)
			(size 0 0)
			(layers "B.Cu" "B.Mask" "B.Paste")
			(net "P3V3_AUX")
		)
		(pad "2" smd circle
			(at -0.40005 0)
			(size 0 0)
			(layers "B.Cu" "B.Mask" "B.Paste")
			(net "PWRGD_P3V3_AUX_R1")
		)
	)
)
